# S9S_MB_2U (Grand Teton) — schematic netlist excerpt (pin names and nets, part order shuffled) for the footprints in the layout excerpt that follows; sources: Cadence DE-HDL packaged netlist, KiCad conversion of 03242023_DA0F0TMBIJ0_F0T_Motherboard_J_brd_V01_OCP.brd

J14  SCONN288_ADR50017P087CC  SCONN288_ADR50017-P087CC IO  pkg DDR288S_1-1VXB  page 95
  VIN_BULK0  = P12V_S3_AUX_CPU0_NVDIMM
  RFU0  = TP_CHG_CPU0_DIMM2_FRU_0
  VIN_MGMT  = P3V3_AUX
  HSCL  = I3C_SPD_DDREFGH_CPU0_LVC1_SCL_5
  HSDA  = I3C_SPD_DDREFGH_CPU0_LVC1_SDA
  VSS0  = GND
  DQ0_A  = M_G_CPU0_SA_DQ<0>
  VSS1  = GND
  DQ1_A  = M_G_CPU0_SA_DQ<1>
  VSS2  = GND
  DQS0_A_T  = M_G_CPU0_SA_DQS_DP<0>
  DQS0_A_C  = M_G_CPU0_SA_DQS_DN<0>
  VSS3  = GND
  DQ4_A  = M_G_CPU0_SA_DQ<4>
  VSS4  = GND
  DQ5_A  = M_G_CPU0_SA_DQ<5>
  VSS5  = GND
  DQ8_A  = M_G_CPU0_SA_DQ<8>
  VSS6  = GND
  DQ9_A  = M_G_CPU0_SA_DQ<9>
  VSS7  = GND
  DQS1_A_T  = M_G_CPU0_SA_DQS_DP<1>
  DQS1_A_C  = M_G_CPU0_SA_DQS_DN<1>
  VSS8  = GND
  DQ12_A  = M_G_CPU0_SA_DQ<12>
  VSS9  = GND
  DQ13_A  = M_G_CPU0_SA_DQ<13>
  VSS10  = GND
  DQ16_A  = M_G_CPU0_SA_DQ<16>
  VSS11  = GND
  DQ17_A  = M_G_CPU0_SA_DQ<17>
  VSS12  = GND
  DQS2_A_T  = M_G_CPU0_SA_DQS_DP<2>
  DQS2_A_C  = M_G_CPU0_SA_DQS_DN<2>
  VSS13  = GND
  DQ20_A  = M_G_CPU0_SA_DQ<20>
  VSS14  = GND
  DQ21_A  = M_G_CPU0_SA_DQ<21>
  VSS15  = GND
  DQ24_A  = M_G_CPU0_SA_DQ<24>
  VSS16  = GND
  DQ25_A  = M_G_CPU0_SA_DQ<25>
  VSS17  = GND
  DQS3_A_T  = M_G_CPU0_SA_DQS_DP<3>
  DQS3_A_C  = M_G_CPU0_SA_DQS_DN<3>
  VSS18  = GND
  DQ28_A  = M_G_CPU0_SA_DQ<28>
  VSS19  = GND
  DQ29_A  = M_G_CPU0_SA_DQ<29>
  VSS20  = GND
  CB0_A  = M_G_CPU0_SA_CB<0>
  VSS21  = GND
  CB1_A  = M_G_CPU0_SA_CB<1>
  VSS22  = GND
  DQS4_A_T  = M_G_CPU0_SA_DQS_DP<4>
  DQS4_A_C  = M_G_CPU0_SA_DQS_DN<4>
  VSS23  = GND
  CB4_A  = M_G_CPU0_SA_CB<4>
  VSS24  = GND
  CB5_A  = M_G_CPU0_SA_CB<5>
  VSS25  = GND
  ALERT_N  = M_G_CPU0_ALERT_N
  VSS26  = GND
  CS0_A_N  = M_G_CPU0_SA_CS_N<2>
  VSS27  = GND
  CA0_A  = M_G_CPU0_SA_CA<0>
  VSS28  = GND
  CA2_A  = M_G_CPU0_SA_CA<2>
  VSS29  = GND
  CA4_A  = M_G_CPU0_SA_CA<4>
  VSS30  = GND
  CA6_A  = M_G_CPU0_SA_CA<6>
  VSS31  = GND
  PAR_A  = M_G_CPU0_SA_PAR
  VSS32  = GND
  CA0_B  = M_G_CPU0_SB_CA<0>
  VSS33  = GND
  CA2_B  = M_G_CPU0_SB_CA<2>
  VSS34  = GND
  CA4_B  = M_G_CPU0_SB_CA<4>
  VSS35  = GND
  CA6_B  = M_G_CPU0_SB_CA<6>
  VSS36  = GND
  CS0_B_N  = M_G_CPU0_SB_CS_N<2>
  VSS37  = GND
  \lbd||rsp_a_n\  = M_G_CPU0_SA_RSP<1>
  \lbs||rsp_b_n\  = M_G_CPU0_SB_RSP<1>
  VSS38  = GND
  CB4_B  = M_G_CPU0_SB_CB<4>
  VSS39  = GND
  CB5_B  = M_G_CPU0_SB_CB<5>
  VSS40  = GND
  \dqs9_b_t||tdqs9_b_t||dbi4_b_n\  = M_G_CPU0_SB_DQS_DP<9>
  \dqs9_b_c||tdqs9_b_c\  = M_G_CPU0_SB_DQS_DN<9>
  VSS41  = GND
  CB0_B  = M_G_CPU0_SB_CB<0>
  VSS42  = GND
  CB1_B  = M_G_CPU0_SB_CB<1>
  VSS43  = GND
  DQ0_B  = M_G_CPU0_SB_DQ<0>
  VSS44  = GND
  DQ1_B  = M_G_CPU0_SB_DQ<1>
  VSS45  = GND
  DQS0_B_T  = M_G_CPU0_SB_DQS_DP<0>
  DQS0_B_C  = M_G_CPU0_SB_DQS_DN<0>
  VSS46  = GND
  DQ4_B  = M_G_CPU0_SB_DQ<4>
  VSS47  = GND
  DQ5_B  = M_G_CPU0_SB_DQ<5>
  VSS48  = GND
  DQ8_B  = M_G_CPU0_SB_DQ<8>
  VSS49  = GND
  DQ9_B  = M_G_CPU0_SB_DQ<9>
  VSS50  = GND
  DQS1_B_T  = M_G_CPU0_SB_DQS_DP<1>
  DQS1_B_C  = M_G_CPU0_SB_DQS_DN<1>
  VSS51  = GND
  DQ12_B  = M_G_CPU0_SB_DQ<12>
  VSS52  = GND
  DQ13_B  = M_G_CPU0_SB_DQ<13>
  VSS53  = GND
  DQ16_B  = M_G_CPU0_SB_DQ<16>
  VSS54  = GND
  DQ17_B  = M_G_CPU0_SB_DQ<17>
  VSS55  = GND
  DQS2_B_T  = M_G_CPU0_SB_DQS_DP<2>
  DQS2_B_C  = M_G_CPU0_SB_DQS_DN<2>
  VSS56  = GND
  DQ20_B  = M_G_CPU0_SB_DQ<20>
  VSS57  = GND
  DQ21_B  = M_G_CPU0_SB_DQ<21>
  VSS58  = GND
  DQ24_B  = M_G_CPU0_SB_DQ<24>
  VSS59  = GND
  DQ25_B  = M_G_CPU0_SB_DQ<25>
  VSS60  = GND
  DQS3_B_T  = M_G_CPU0_SB_DQS_DP<3>
  DQS3_B_C  = M_G_CPU0_SB_DQS_DN<3>
  VSS61  = GND
  DQ28_B  = M_G_CPU0_SB_DQ<28>
  VSS62  = GND
  DQ29_B  = M_G_CPU0_SB_DQ<29>
  VSS63  = GND
  RFU1  = TP_CHG_CPU0_DIMM2_FRU_1
  VIN_BULK1  = P12V_S3_AUX_CPU0_NVDIMM
  VIN_BULK2  = P12V_S3_AUX_CPU0_NVDIMM
  \pwr_good||fail_n\  = PWRGD_CHG_CPU0_DIMM2
  HSA  = PD_CHG_CPU0_DIMM2_SAA
  RFU2  = TP_CHG_CPU0_DIMM2_FRU_2
  RFU3  = TP_CHG_CPU0_DIMM2_FRU_3
  VSS64  = GND
  DQ2_A  = M_G_CPU0_SA_DQ<2>
  VSS65  = GND
  DQ3_A  = M_G_CPU0_SA_DQ<3>
  VSS66  = GND
  \dqs5_a_c||tdqs5_a_c||dqs5_a_t||tdqs5_a_t\  = M_G_CPU0_SA_DQS_DN<5>
  \dqs5_a_t||tdqs5_a_t\  = M_G_CPU0_SA_DQS_DP<5>
  VSS67  = GND
  DQ6_A  = M_G_CPU0_SA_DQ<6>
  VSS68  = GND
  DQ7_A  = M_G_CPU0_SA_DQ<7>
  VSS69  = GND
  DQ10_A  = M_G_CPU0_SA_DQ<10>
  VSS70  = GND
  DQ11_A  = M_G_CPU0_SA_DQ<11>
  VSS71  = GND
  \dqs6_a_c||tdqs6_a_c||dqs6_a_t||tdqs6_a_t\  = M_G_CPU0_SA_DQS_DN<6>
  \dqs6_a_t||tdqs6_a_t\  = M_G_CPU0_SA_DQS_DP<6>
  VSS72  = GND
  DQ14_A  = M_G_CPU0_SA_DQ<14>
  VSS73  = GND
  DQ15_A  = M_G_CPU0_SA_DQ<15>
  VSS74  = GND
  DQ18_A  = M_G_CPU0_SA_DQ<18>
  VSS75  = GND
  DQ19_A  = M_G_CPU0_SA_DQ<19>
  VSS76  = GND
  \dqs7_a_c||tdqs7_a_c\  = M_G_CPU0_SA_DQS_DN<7>
  \dqs7_a_t||tdqs7_a_t\  = M_G_CPU0_SA_DQS_DP<7>
  VSS77  = GND
  DQ22_A  = M_G_CPU0_SA_DQ<22>
  VSS78  = GND
  DQ23_A  = M_G_CPU0_SA_DQ<23>
  VSS79  = GND
  DQ26_A  = M_G_CPU0_SA_DQ<26>
  VSS80  = GND
  DQ27_A  = M_G_CPU0_SA_DQ<27>
  VSS81  = GND
  \dqs8_a_c||tdqs8_a_c\  = M_G_CPU0_SA_DQS_DN<8>
  \dqs8_a_t||tdqs8_a_t\  = M_G_CPU0_SA_DQS_DP<8>
  VSS82  = GND
  DQ30_A  = M_G_CPU0_SA_DQ<30>
  VSS83  = GND
  DQ31_A  = M_G_CPU0_SA_DQ<31>
  VSS84  = GND
  CB2_A  = M_G_CPU0_SA_CB<2>
  VSS85  = GND
  CB3_A  = M_G_CPU0_SA_CB<3>
  VSS86  = GND
  \dqs9_a_c||tdqs9_a_c\  = M_G_CPU0_SA_DQS_DN<9>
  \dqs9_a_t||tdqs9_a_t\  = M_G_CPU0_SA_DQS_DP<9>
  VSS87  = GND
  CB6_A  = M_G_CPU0_SA_CB<6>
  VSS88  = GND
  CB7_A  = M_G_CPU0_SA_CB<7>
  VSS89  = GND
  RESET_N  = RST_M_GH_CPU0_FPGA_N
  VSS90  = GND
  CS1_A_N  = M_G_CPU0_SA_CS_N<3>
  VSS91  = GND
  CA1_A  = M_G_CPU0_SA_CA<1>
  VSS92  = GND
  CA3_A  = M_G_CPU0_SA_CA<3>
  VSS93  = GND
  CA5_A  = M_G_CPU0_SA_CA<5>
  VSS94  = GND
  CK_T  = M_G_CPU0_CLK_DP<1>
  CK_C  = M_G_CPU0_CLK_DN<1>
  VSS95  = GND
  RFU4  = TP_CHG_CPU0_DIMM2_FRU_4
  CA1_B  = M_G_CPU0_SB_CA<1>
  VSS96  = GND
  CA3_B  = M_G_CPU0_SB_CA<3>
  VSS97  = GND
  CA5_B  = M_G_CPU0_SB_CA<5>
  VSS98  = GND
  PAR_B  = M_G_CPU0_SB_PAR
  VSS99  = GND
  CS1_B_N  = M_G_CPU0_SB_CS_N<3>
  VSS100  = GND
  RFU5  = TP_CHG_CPU0_DIMM2_FRU_5
  RFU6  = TP_CHG_CPU0_DIMM2_FRU_6
  VSS101  = GND
  CB6_B  = M_G_CPU0_SB_CB<6>
  VSS102  = GND
  CB7_B  = M_G_CPU0_SB_CB<7>
  VSS103  = GND
  DQS4_B_C  = M_G_CPU0_SB_DQS_DN<4>
  DQS4_B_T  = M_G_CPU0_SB_DQS_DP<4>
  VSS104  = GND
  CB2_B  = M_G_CPU0_SB_CB<2>
  VSS105  = GND
  CB3_B  = M_G_CPU0_SB_CB<3>
  VSS106  = GND
  DQ2_B  = M_G_CPU0_SB_DQ<2>
  VSS107  = GND
  DQ3_B  = M_G_CPU0_SB_DQ<3>
  VSS108  = GND
  \dqs5_b_c||tdqs5_b_c\  = M_G_CPU0_SB_DQS_DN<5>
  \dqs5_b_t||tdqs5_b_t\  = M_G_CPU0_SB_DQS_DP<5>
  VSS109  = GND
  DQ6_B  = M_G_CPU0_SB_DQ<6>
  VSS110  = GND
  DQ7_B  = M_G_CPU0_SB_DQ<7>
  VSS111  = GND
  DQ10_B  = M_G_CPU0_SB_DQ<10>
  VSS112  = GND
  DQ11_B  = M_G_CPU0_SB_DQ<11>
  VSS113  = GND
  \dqs6_b_c||tdqs6_b_c\  = M_G_CPU0_SB_DQS_DN<6>
  \dqs6_b_t||tdqs6_b_t\  = M_G_CPU0_SB_DQS_DP<6>
  VSS114  = GND
  DQ14_B  = M_G_CPU0_SB_DQ<14>
  VSS115  = GND
  DQ15_B  = M_G_CPU0_SB_DQ<15>
  VSS116  = GND
  DQ18_B  = M_G_CPU0_SB_DQ<18>
  VSS117  = GND
  DQ19_B  = M_G_CPU0_SB_DQ<19>
  VSS118  = GND
  \dqs7_b_c||tdqs7_b_c\  = M_G_CPU0_SB_DQS_DN<7>
  \dqs7_b_t||tdqs7_b_t\  = M_G_CPU0_SB_DQS_DP<7>
  VSS119  = GND
  DQ22_B  = M_G_CPU0_SB_DQ<22>
  VSS120  = GND
  DQ23_B  = M_G_CPU0_SB_DQ<23>
  VSS121  = GND
  DQ26_B  = M_G_CPU0_SB_DQ<26>
  VSS122  = GND
  DQ27_B  = M_G_CPU0_SB_DQ<27>
  VSS123  = GND
  \dqs8_b_c||tdqs8_b_c\  = M_G_CPU0_SB_DQS_DN<8>
  \dqs8_b_t||tdqs8_b_t\  = M_G_CPU0_SB_DQS_DP<8>
  VSS124  = GND
  DQ30_B  = M_G_CPU0_SB_DQ<30>
  VSS125  = GND
  DQ31_B  = M_G_CPU0_SB_DQ<31>
  VSS126  = GND
  G1  = GND
  G2  = GND
  G3  = GND

(kicad_pcb
	(version 20260206)
	(generator "pcbnew")
	(generator_version "10.0")
	(general
		(thickness 1.6)
		(legacy_teardrops no)
	)
	(paper "A4")
	(title_block
		(title "03242023_DA0F0TMBIJ0_F0T_Motherboard_J_brd_V01_OCP.brd")
		(comment 1 "Grand Teton / footprint 3833 of 6105 (J14), pads 92-137 of 291")
	)
	(layers
		(0 "F.Cu" signal "TOP")
		(4 "In1.Cu" signal "GND")
		(6 "In2.Cu" signal "IN1")
		(8 "In3.Cu" signal "GND1")
		(10 "In4.Cu" signal "IN2")
		(12 "In5.Cu" signal "GND2")
		(14 "In6.Cu" signal "IN3")
		(16 "In7.Cu" signal "GND3")
		(18 "In8.Cu" signal "VCC")
		(20 "In9.Cu" signal "VCC1")
		(22 "In10.Cu" signal "GND4")
		(24 "In11.Cu" signal "IN4")
		(26 "In12.Cu" signal "GND5")
		(28 "In13.Cu" signal "IN5")
		(30 "In14.Cu" signal "GND6")
		(32 "In15.Cu" signal "IN6")
		(34 "In16.Cu" signal "GND7")
		(2 "B.Cu" signal "BOTTOM")
		(9 "F.Adhes" user "F.Adhesive")
		(11 "B.Adhes" user "B.Adhesive")
		(13 "F.Paste" user "Package Geometry/Pastemask Top")
		(15 "B.Paste" user "Package Geometry/Pastemask Bottom")
		(5 "F.SilkS" user "Ref Des/Silkscreen Top")
		(7 "B.SilkS" user "Ref Des/Silkscreen Bottom")
		(1 "F.Mask" user "Board Geometry/Soldermask Top")
		(3 "B.Mask" user "Board Geometry/Soldermask Bottom")
		(17 "Dwgs.User" user "User.Drawings")
		(19 "Cmts.User" user "User.Comments")
		(21 "Eco1.User" user "User.Eco1")
		(23 "Eco2.User" user "User.Eco2")
		(25 "Edge.Cuts" user "Board Geometry/Outline")
		(27 "Margin" user)
		(31 "F.CrtYd" user "Package Geometry/Place Bound Top")
		(29 "B.CrtYd" user "Package Geometry/Place Bound Bottom")
		(35 "F.Fab" user "Ref Des/Assembly Top")
		(33 "B.Fab" user "Ref Des/Assembly Bottom")
	)
	(footprint ""
		(layer "F.Cu")
		(at 438.978548 -258.091686)
		(property "Reference" "J14"
			(at -3.683 -81.702148 0)
			(unlocked yes)
			(layer "F.SilkS")
			(effects
				(font
					(size 0.7874 0.5842)
					(thickness 0.1524)
				)
				(justify left)
			)
		)
		(property "Value" ""
			(at 0 0 0)
			(layer "F.Fab")
			(effects
				(font
					(size 1.27 1.27)
				)
			)
		)
		(duplicate_pad_numbers_are_jumpers no)
		(pad "92" smd rect
			(at -2.050034 19.12493 270)
			(size 0.519938 1.4986)
			(layers "F.Cu" "F.Mask" "F.Paste")
			(net "GND")
		)
		(pad "93" smd rect
			(at -2.050034 19.975068 270)
			(size 0.519938 1.4986)
			(layers "F.Cu" "F.Mask" "F.Paste")
			(net "M_G_CPU0_SB_DQS_DP<9>")
		)
		(pad "94" smd rect
			(at -2.050034 20.824952 270)
			(size 0.519938 1.4986)
			(layers "F.Cu" "F.Mask" "F.Paste")
			(net "M_G_CPU0_SB_DQS_DN<9>")
		)
		(pad "95" smd rect
			(at -2.050034 21.67509 270)
			(size 0.519938 1.4986)
			(layers "F.Cu" "F.Mask" "F.Paste")
			(net "GND")
		)
		(pad "96" smd rect
			(at -2.050034 22.524974 270)
			(size 0.519938 1.4986)
			(layers "F.Cu" "F.Mask" "F.Paste")
			(net "M_G_CPU0_SB_CB<0>")
		)
		(pad "97" smd rect
			(at -2.050034 23.375112 270)
			(size 0.519938 1.4986)
			(layers "F.Cu" "F.Mask" "F.Paste")
			(net "GND")
		)
		(pad "98" smd rect
			(at -2.050034 24.224996 270)
			(size 0.519938 1.4986)
			(layers "F.Cu" "F.Mask" "F.Paste")
			(net "M_G_CPU0_SB_CB<1>")
		)
		(pad "99" smd rect
			(at -2.050034 25.07488 270)
			(size 0.519938 1.4986)
			(layers "F.Cu" "F.Mask" "F.Paste")
			(net "GND")
		)
		(pad "100" smd rect
			(at -2.050034 25.925018 270)
			(size 0.519938 1.4986)
			(layers "F.Cu" "F.Mask" "F.Paste")
			(net "M_G_CPU0_SB_DQ<0>")
		)
		(pad "101" smd rect
			(at -2.050034 26.774902 270)
			(size 0.519938 1.4986)
			(layers "F.Cu" "F.Mask" "F.Paste")
			(net "GND")
		)
		(pad "102" smd rect
			(at -2.050034 27.62504 270)
			(size 0.519938 1.4986)
			(layers "F.Cu" "F.Mask" "F.Paste")
			(net "M_G_CPU0_SB_DQ<1>")
		)
		(pad "103" smd rect
			(at -2.050034 28.474924 270)
			(size 0.519938 1.4986)
			(layers "F.Cu" "F.Mask" "F.Paste")
			(net "GND")
		)
		(pad "104" smd rect
			(at -2.050034 29.325062 270)
			(size 0.519938 1.4986)
			(layers "F.Cu" "F.Mask" "F.Paste")
			(net "M_G_CPU0_SB_DQS_DP<0>")
		)
		(pad "105" smd rect
			(at -2.050034 30.174946 270)
			(size 0.519938 1.4986)
			(layers "F.Cu" "F.Mask" "F.Paste")
			(net "M_G_CPU0_SB_DQS_DN<0>")
		)
		(pad "106" smd rect
			(at -2.050034 31.025084 270)
			(size 0.519938 1.4986)
			(layers "F.Cu" "F.Mask" "F.Paste")
			(net "GND")
		)
		(pad "107" smd rect
			(at -2.050034 31.874968 270)
			(size 0.519938 1.4986)
			(layers "F.Cu" "F.Mask" "F.Paste")
			(net "M_G_CPU0_SB_DQ<4>")
		)
		(pad "108" smd rect
			(at -2.050034 32.725106 270)
			(size 0.519938 1.4986)
			(layers "F.Cu" "F.Mask" "F.Paste")
			(net "GND")
		)
		(pad "109" smd rect
			(at -2.050034 33.57499 270)
			(size 0.519938 1.4986)
			(layers "F.Cu" "F.Mask" "F.Paste")
			(net "M_G_CPU0_SB_DQ<5>")
		)
		(pad "110" smd rect
			(at -2.050034 34.425128 270)
			(size 0.519938 1.4986)
			(layers "F.Cu" "F.Mask" "F.Paste")
			(net "GND")
		)
		(pad "111" smd rect
			(at -2.050034 35.275012 270)
			(size 0.519938 1.4986)
			(layers "F.Cu" "F.Mask" "F.Paste")
			(net "M_G_CPU0_SB_DQ<8>")
		)
		(pad "112" smd rect
			(at -2.050034 36.124896 270)
			(size 0.519938 1.4986)
			(layers "F.Cu" "F.Mask" "F.Paste")
			(net "GND")
		)
		(pad "113" smd rect
			(at -2.050034 36.975034 270)
			(size 0.519938 1.4986)
			(layers "F.Cu" "F.Mask" "F.Paste")
			(net "M_G_CPU0_SB_DQ<9>")
		)
		(pad "114" smd rect
			(at -2.050034 37.824918 270)
			(size 0.519938 1.4986)
			(layers "F.Cu" "F.Mask" "F.Paste")
			(net "GND")
		)
		(pad "115" smd rect
			(at -2.050034 38.675056 270)
			(size 0.519938 1.4986)
			(layers "F.Cu" "F.Mask" "F.Paste")
			(net "M_G_CPU0_SB_DQS_DP<1>")
		)
		(pad "116" smd rect
			(at -2.050034 39.52494 270)
			(size 0.519938 1.4986)
			(layers "F.Cu" "F.Mask" "F.Paste")
			(net "M_G_CPU0_SB_DQS_DN<1>")
		)
		(pad "117" smd rect
			(at -2.050034 40.375078 270)
			(size 0.519938 1.4986)
			(layers "F.Cu" "F.Mask" "F.Paste")
			(net "GND")
		)
		(pad "118" smd rect
			(at -2.050034 41.224962 270)
			(size 0.519938 1.4986)
			(layers "F.Cu" "F.Mask" "F.Paste")
			(net "M_G_CPU0_SB_DQ<12>")
		)
		(pad "119" smd rect
			(at -2.050034 42.0751 270)
			(size 0.519938 1.4986)
			(layers "F.Cu" "F.Mask" "F.Paste")
			(net "GND")
		)
		(pad "120" smd rect
			(at -2.050034 42.924984 270)
			(size 0.519938 1.4986)
			(layers "F.Cu" "F.Mask" "F.Paste")
			(net "M_G_CPU0_SB_DQ<13>")
		)
		(pad "121" smd rect
			(at -2.050034 43.775122 270)
			(size 0.519938 1.4986)
			(layers "F.Cu" "F.Mask" "F.Paste")
			(net "GND")
		)
		(pad "122" smd rect
			(at -2.050034 44.625006 270)
			(size 0.519938 1.4986)
			(layers "F.Cu" "F.Mask" "F.Paste")
			(net "M_G_CPU0_SB_DQ<16>")
		)
		(pad "123" smd rect
			(at -2.050034 45.47489 270)
			(size 0.519938 1.4986)
			(layers "F.Cu" "F.Mask" "F.Paste")
			(net "GND")
		)
		(pad "124" smd rect
			(at -2.050034 46.325028 270)
			(size 0.519938 1.4986)
			(layers "F.Cu" "F.Mask" "F.Paste")
			(net "M_G_CPU0_SB_DQ<17>")
		)
		(pad "125" smd rect
			(at -2.050034 47.174912 270)
			(size 0.519938 1.4986)
			(layers "F.Cu" "F.Mask" "F.Paste")
			(net "GND")
		)
		(pad "126" smd rect
			(at -2.050034 48.02505 270)
			(size 0.519938 1.4986)
			(layers "F.Cu" "F.Mask" "F.Paste")
			(net "M_G_CPU0_SB_DQS_DP<2>")
		)
		(pad "127" smd rect
			(at -2.050034 48.874934 270)
			(size 0.519938 1.4986)
			(layers "F.Cu" "F.Mask" "F.Paste")
			(net "M_G_CPU0_SB_DQS_DN<2>")
		)
		(pad "128" smd rect
			(at -2.050034 49.725072 270)
			(size 0.519938 1.4986)
			(layers "F.Cu" "F.Mask" "F.Paste")
			(net "GND")
		)
		(pad "129" smd rect
			(at -2.050034 50.574956 270)
			(size 0.519938 1.4986)
			(layers "F.Cu" "F.Mask" "F.Paste")
			(net "M_G_CPU0_SB_DQ<20>")
		)
		(pad "130" smd rect
			(at -2.050034 51.425094 270)
			(size 0.519938 1.4986)
			(layers "F.Cu" "F.Mask" "F.Paste")
			(net "GND")
		)
		(pad "131" smd rect
			(at -2.050034 52.274978 270)
			(size 0.519938 1.4986)
			(layers "F.Cu" "F.Mask" "F.Paste")
			(net "M_G_CPU0_SB_DQ<21>")
		)
		(pad "132" smd rect
			(at -2.050034 53.125116 270)
			(size 0.519938 1.4986)
			(layers "F.Cu" "F.Mask" "F.Paste")
			(net "GND")
		)
		(pad "133" smd rect
			(at -2.050034 53.975 270)
			(size 0.519938 1.4986)
			(layers "F.Cu" "F.Mask" "F.Paste")
			(net "M_G_CPU0_SB_DQ<24>")
		)
		(pad "134" smd rect
			(at -2.050034 54.824884 270)
			(size 0.519938 1.4986)
			(layers "F.Cu" "F.Mask" "F.Paste")
			(net "GND")
		)
		(pad "135" smd rect
			(at -2.050034 55.675022 270)
			(size 0.519938 1.4986)
			(layers "F.Cu" "F.Mask" "F.Paste")
			(net "M_G_CPU0_SB_DQ<25>")
		)
		(pad "136" smd rect
			(at -2.050034 56.524906 270)
			(size 0.519938 1.4986)
			(layers "F.Cu" "F.Mask" "F.Paste")
			(net "GND")
		)
		(pad "137" smd rect
			(at -2.050034 57.375044 270)
			(size 0.519938 1.4986)
			(layers "F.Cu" "F.Mask" "F.Paste")
			(net "M_G_CPU0_SB_DQS_DP<3>")
		)
	)
)
